FILE_TYPE=LIBRARY_PARTS;
primitive 'AT24C64';
  pin
    'A0':
      PIN_NUMBER='(1)';
      INPUT_LOAD='(-0.01,0.01)';
    'A1':
      PIN_NUMBER='(2)';
      INPUT_LOAD='(-0.01,0.01)';
    'A2':
      PIN_NUMBER='(3)';
      INPUT_LOAD='(-0.01,0.01)';
    'SCL':
      PIN_NUMBER='(6)';
      INPUT_LOAD='(-0.01,0.01)';
    'WP':
      PIN_NUMBER='(7)';
      INPUT_LOAD='(-0.01,0.01)';
    'SDA':
      PIN_NUMBER='(5)';
      INPUT_LOAD='(-0.01,0.01)';
      OUTPUT_LOAD='(1.00,-1.00)';
      OUTPUT_TYPE='(TS,TS)';
      BIDIRECTIONAL='TRUE';
  end_pin;
  body
    POWER_PINS='(VCC:8)';
    POWER_PINS='(GND:4)';
    CLASS='IC';
    PART_NAME='at24c64';
    PHYS_DES_PREFIX='U';
  end_body;
end_primitive;
END.
